(kicad_pcb
	(version 20260206)
	(generator "pcbnew")
	(generator_version "10.0")
	(general
		(thickness 1.6)
		(legacy_teardrops no)
	)
	(paper "A4")
	(title_block
		(title "03242023_DA0F0TMBIJ0_F0T_Motherboard_J_brd_V01_OCP.brd")
		(comment 1 "Grand Teton / footprints 5317-5322 of 6105")
	)
	(layers
		(0 "F.Cu" signal "TOP")
		(4 "In1.Cu" signal "GND")
		(6 "In2.Cu" signal "IN1")
		(8 "In3.Cu" signal "GND1")
		(10 "In4.Cu" signal "IN2")
		(12 "In5.Cu" signal "GND2")
		(14 "In6.Cu" signal "IN3")
		(16 "In7.Cu" signal "GND3")
		(18 "In8.Cu" signal "VCC")
		(20 "In9.Cu" signal "VCC1")
		(22 "In10.Cu" signal "GND4")
		(24 "In11.Cu" signal "IN4")
		(26 "In12.Cu" signal "GND5")
		(28 "In13.Cu" signal "IN5")
		(30 "In14.Cu" signal "GND6")
		(32 "In15.Cu" signal "IN6")
		(34 "In16.Cu" signal "GND7")
		(2 "B.Cu" signal "BOTTOM")
		(9 "F.Adhes" user "F.Adhesive")
		(11 "B.Adhes" user "B.Adhesive")
		(13 "F.Paste" user "Package Geometry/Pastemask Top")
		(15 "B.Paste" user "Package Geometry/Pastemask Bottom")
		(5 "F.SilkS" user "Ref Des/Silkscreen Top")
		(7 "B.SilkS" user "Ref Des/Silkscreen Bottom")
		(1 "F.Mask" user "Board Geometry/Soldermask Top")
		(3 "B.Mask" user "Board Geometry/Soldermask Bottom")
		(17 "Dwgs.User" user "User.Drawings")
		(19 "Cmts.User" user "User.Comments")
		(21 "Eco1.User" user "User.Eco1")
		(23 "Eco2.User" user "User.Eco2")
		(25 "Edge.Cuts" user "Board Geometry/Outline")
		(27 "Margin" user)
		(31 "F.CrtYd" user "Package Geometry/Place Bound Top")
		(29 "B.CrtYd" user "Package Geometry/Place Bound Bottom")
		(35 "F.Fab" user "Ref Des/Assembly Top")
		(33 "B.Fab" user "Ref Des/Assembly Bottom")
	)
	(footprint ""
		(layer "B.Cu")
		(at 34.846514 -165.841426)
		(property "Reference" "PR1400"
			(at 0 0 0)
			(layer "B.SilkS")
			(hide yes)
			(effects
				(font
					(size 1.27 1.27)
				)
				(justify mirror)
			)
		)
		(property "Value" ""
			(at 0 0 0)
			(layer "B.Fab")
			(effects
				(font
					(size 1.27 1.27)
				)
				(justify mirror)
			)
		)
		(duplicate_pad_numbers_are_jumpers no)
		(fp_line
			(start -0.7874 -0.4064)
			(end -0.7874 0.4064)
			(stroke
				(width 0.1524)
				(type default)
			)
			(layer "B.SilkS")
		)
		(fp_line
			(start -0.7874 0.4064)
			(end 0.7874 0.4064)
			(stroke
				(width 0.1524)
				(type default)
			)
			(layer "B.SilkS")
		)
		(fp_line
			(start 0.7874 -0.4064)
			(end -0.7874 -0.4064)
			(stroke
				(width 0.1524)
				(type default)
			)
			(layer "B.SilkS")
		)
		(fp_line
			(start 0.7874 0.4064)
			(end 0.7874 -0.4064)
			(stroke
				(width 0.1524)
				(type default)
			)
			(layer "B.SilkS")
		)
		(fp_line
			(start -0.67945 -0.3048)
			(end -0.67945 0.3048)
			(stroke
				(width 0.1)
				(type default)
			)
			(layer "B.Fab")
		)
		(fp_line
			(start -0.67945 0.3048)
			(end -0.120396 0.3048)
			(stroke
				(width 0.1)
				(type default)
			)
			(layer "B.Fab")
		)
		(fp_line
			(start -0.12065 -0.3048)
			(end -0.67945 -0.3048)
			(stroke
				(width 0.1)
				(type default)
			)
			(layer "B.Fab")
		)
		(fp_line
			(start -0.12065 -0.2794)
			(end -0.12065 -0.3048)
			(stroke
				(width 0.1)
				(type default)
			)
			(layer "B.Fab")
		)
		(fp_line
			(start -0.120396 0.2794)
			(end 0.12065 0.2794)
			(stroke
				(width 0.1)
				(type default)
			)
			(layer "B.Fab")
		)
		(fp_line
			(start -0.120396 0.3048)
			(end -0.120396 0.2794)
			(stroke
				(width 0.1)
				(type default)
			)
			(layer "B.Fab")
		)
		(fp_line
			(start 0.12065 -0.305054)
			(end 0.12065 -0.2794)
			(stroke
				(width 0.1)
				(type default)
			)
			(layer "B.Fab")
		)
		(fp_line
			(start 0.12065 -0.2794)
			(end -0.12065 -0.2794)
			(stroke
				(width 0.1)
				(type default)
			)
			(layer "B.Fab")
		)
		(fp_line
			(start 0.12065 0.2794)
			(end 0.12065 0.3048)
			(stroke
				(width 0.1)
				(type default)
			)
			(layer "B.Fab")
		)
		(fp_line
			(start 0.12065 0.3048)
			(end 0.67945 0.3048)
			(stroke
				(width 0.1)
				(type default)
			)
			(layer "B.Fab")
		)
		(fp_line
			(start 0.67945 -0.305054)
			(end 0.12065 -0.305054)
			(stroke
				(width 0.1)
				(type default)
			)
			(layer "B.Fab")
		)
		(fp_line
			(start 0.67945 0.3048)
			(end 0.67945 -0.305054)
			(stroke
				(width 0.1)
				(type default)
			)
			(layer "B.Fab")
		)
		(pad "1" smd circle
			(at 0.40005 0 180)
			(size 0 0)
			(layers "B.Cu" "B.Mask" "B.Paste")
			(net "P12V_AUX_CPU1_DIMM_ISEN_P")
		)
		(pad "2" smd circle
			(at -0.40005 0 180)
			(size 0 0)
			(layers "B.Cu" "B.Mask" "B.Paste")
			(net "PVCCD_HV_CPU1_ISENSE_P")
		)
	)
	(footprint ""
		(layer "B.Cu")
		(at 28.574238 -130.877056 -90)
		(property "Reference" "PR667"
			(at 0 0 90)
			(layer "B.SilkS")
			(hide yes)
			(effects
				(font
					(size 1.27 1.27)
				)
				(justify mirror)
			)
		)
		(property "Value" ""
			(at 0 0 90)
			(layer "B.Fab")
			(effects
				(font
					(size 1.27 1.27)
				)
				(justify mirror)
			)
		)
		(duplicate_pad_numbers_are_jumpers no)
		(fp_line
			(start -0.7874 0.4064)
			(end 0.7874 0.4064)
			(stroke
				(width 0.1524)
				(type default)
			)
			(layer "B.SilkS")
		)
		(fp_line
			(start 0.7874 0.4064)
			(end 0.7874 -0.4064)
			(stroke
				(width 0.1524)
				(type default)
			)
			(layer "B.SilkS")
		)
		(fp_line
			(start -0.7874 -0.4064)
			(end -0.7874 0.4064)
			(stroke
				(width 0.1524)
				(type default)
			)
			(layer "B.SilkS")
		)
		(fp_line
			(start 0.7874 -0.4064)
			(end -0.7874 -0.4064)
			(stroke
				(width 0.1524)
				(type default)
			)
			(layer "B.SilkS")
		)
		(fp_line
			(start -0.67945 0.3048)
			(end -0.120396 0.3048)
			(stroke
				(width 0.1)
				(type default)
			)
			(layer "B.Fab")
		)
		(fp_line
			(start -0.120396 0.3048)
			(end -0.120396 0.2794)
			(stroke
				(width 0.1)
				(type default)
			)
			(layer "B.Fab")
		)
		(fp_line
			(start 0.12065 0.3048)
			(end 0.67945 0.3048)
			(stroke
				(width 0.1)
				(type default)
			)
			(layer "B.Fab")
		)
		(fp_line
			(start 0.67945 0.3048)
			(end 0.67945 -0.305054)
			(stroke
				(width 0.1)
				(type default)
			)
			(layer "B.Fab")
		)
		(fp_line
			(start -0.120396 0.2794)
			(end 0.12065 0.2794)
			(stroke
				(width 0.1)
				(type default)
			)
			(layer "B.Fab")
		)
		(fp_line
			(start 0.12065 0.2794)
			(end 0.12065 0.3048)
			(stroke
				(width 0.1)
				(type default)
			)
			(layer "B.Fab")
		)
		(fp_line
			(start -0.12065 -0.2794)
			(end -0.12065 -0.3048)
			(stroke
				(width 0.1)
				(type default)
			)
			(layer "B.Fab")
		)
		(fp_line
			(start 0.12065 -0.2794)
			(end -0.12065 -0.2794)
			(stroke
				(width 0.1)
				(type default)
			)
			(layer "B.Fab")
		)
		(fp_line
			(start -0.67945 -0.3048)
			(end -0.67945 0.3048)
			(stroke
				(width 0.1)
				(type default)
			)
			(layer "B.Fab")
		)
		(fp_line
			(start -0.12065 -0.3048)
			(end -0.67945 -0.3048)
			(stroke
				(width 0.1)
				(type default)
			)
			(layer "B.Fab")
		)
		(fp_line
			(start 0.12065 -0.305054)
			(end 0.12065 -0.2794)
			(stroke
				(width 0.1)
				(type default)
			)
			(layer "B.Fab")
		)
		(fp_line
			(start 0.67945 -0.305054)
			(end 0.12065 -0.305054)
			(stroke
				(width 0.1)
				(type default)
			)
			(layer "B.Fab")
		)
		(pad "1" smd circle
			(at 0.40005 0 90)
			(size 0 0)
			(layers "B.Cu" "B.Mask" "B.Paste")
			(net "PVCCFA_EHV_CPU1_BTSEN")
		)
		(pad "2" smd circle
			(at -0.40005 0 90)
			(size 0 0)
			(layers "B.Cu" "B.Mask" "B.Paste")
			(net "GND")
		)
	)
	(footprint ""
		(layer "B.Cu")
		(at 178.1556 -112.57534 90)
		(property "Reference" "C1931"
			(at 0 0 90)
			(layer "B.SilkS")
			(hide yes)
			(effects
				(font
					(size 1.27 1.27)
				)
				(justify mirror)
			)
		)
		(property "Value" ""
			(at 0 0 90)
			(layer "B.Fab")
			(effects
				(font
					(size 1.27 1.27)
				)
				(justify mirror)
			)
		)
		(duplicate_pad_numbers_are_jumpers no)
		(fp_line
			(start 0.69215 -0.2921)
			(end -0.69215 -0.2921)
			(stroke
				(width 0.1524)
				(type default)
			)
			(layer "B.SilkS")
		)
		(fp_line
			(start -0.69215 -0.2921)
			(end -0.69215 0.2921)
			(stroke
				(width 0.1524)
				(type default)
			)
			(layer "B.SilkS")
		)
		(fp_line
			(start 0.69215 0.2921)
			(end 0.69215 -0.2921)
			(stroke
				(width 0.1524)
				(type default)
			)
			(layer "B.SilkS")
		)
		(fp_line
			(start -0.69215 0.2921)
			(end 0.69215 0.2921)
			(stroke
				(width 0.1524)
				(type default)
			)
			(layer "B.SilkS")
		)
		(fp_line
			(start 0.51435 -0.2794)
			(end -0.51435 -0.2794)
			(stroke
				(width 0.1)
				(type default)
			)
			(layer "B.Fab")
		)
		(fp_line
			(start -0.51435 -0.2794)
			(end -0.51435 0.2794)
			(stroke
				(width 0.1)
				(type default)
			)
			(layer "B.Fab")
		)
		(fp_line
			(start 0.51435 0.2794)
			(end 0.51435 -0.2794)
			(stroke
				(width 0.1)
				(type default)
			)
			(layer "B.Fab")
		)
		(fp_line
			(start -0.51435 0.2794)
			(end 0.51435 0.2794)
			(stroke
				(width 0.1)
				(type default)
			)
			(layer "B.Fab")
		)
		(pad "1" smd circle
			(at 0.40005 0 270)
			(size 0 0)
			(layers "B.Cu" "B.Mask" "B.Paste")
			(net "VCC_PLD_CORE")
		)
		(pad "2" smd circle
			(at -0.40005 0 270)
			(size 0 0)
			(layers "B.Cu" "B.Mask" "B.Paste")
			(net "GND")
		)
		(zone
			(layer "B.Cu")
			(hatch none 0.5)
			(connect_pads
				(clearance 0)
			)
			(min_thickness 0.25)
			(keepout
				(tracks not_allowed)
				(vias allowed)
				(pads allowed)
				(copperpour not_allowed)
				(footprints allowed)
			)
			(placement
				(enabled no)
				(sheetname "")
			)
			(fill
				(thermal_gap 0.5)
				(thermal_bridge_width 0.5)
				(island_removal_mode 0)
			)
			(polygon
				(pts
					(xy 178.24323 -112.76584) (xy 178.301396 -112.6744) (xy 178.301396 -112.47501) (xy 178.24323 -112.38484)
					(xy 178.06797 -112.38484) (xy 178.00955 -112.47501) (xy 178.00955 -112.6744) (xy 178.067716 -112.76584)
				)
			)
		)
	)
	(footprint ""
		(layer "B.Cu")
		(at 410.902658 -153.147522 180)
		(property "Reference" "PC1900"
			(at 0 0 0)
			(layer "B.SilkS")
			(hide yes)
			(effects
				(font
					(size 1.27 1.27)
				)
				(justify mirror)
			)
		)
		(property "Value" ""
			(at 0 0 0)
			(layer "B.Fab")
			(effects
				(font
					(size 1.27 1.27)
				)
				(justify mirror)
			)
		)
		(duplicate_pad_numbers_are_jumpers no)
		(fp_line
			(start 4.533392 2.249932)
			(end 4.533392 -2.249932)
			(stroke
				(width 0.1524)
				(type default)
			)
			(layer "B.SilkS")
		)
		(fp_line
			(start 4.533392 -2.249932)
			(end -4.533392 -2.249932)
			(stroke
				(width 0.1524)
				(type default)
			)
			(layer "B.SilkS")
		)
		(fp_line
			(start -4.533392 2.249932)
			(end 4.533392 2.249932)
			(stroke
				(width 0.1524)
				(type default)
			)
			(layer "B.SilkS")
		)
		(fp_line
			(start -4.533392 -2.249932)
			(end -4.533392 2.249932)
			(stroke
				(width 0.1524)
				(type default)
			)
			(layer "B.SilkS")
		)
		(fp_rect
			(start 5.39242 -2.326132)
			(end 4.533392 2.326132)
			(stroke
				(width 0)
				(type default)
			)
			(fill yes)
			(layer "B.SilkS")
		)
		(fp_line
			(start 3.750056 2.249932)
			(end 3.750056 -2.249932)
			(stroke
				(width 0.1)
				(type default)
			)
			(layer "B.Fab")
		)
		(fp_line
			(start 3.750056 -2.249932)
			(end -3.750056 -2.249932)
			(stroke
				(width 0.1)
				(type default)
			)
			(layer "B.Fab")
		)
		(fp_line
			(start -3.750056 2.249932)
			(end 3.750056 2.249932)
			(stroke
				(width 0.1)
				(type default)
			)
			(layer "B.Fab")
		)
		(fp_line
			(start -3.750056 -2.249932)
			(end -3.750056 2.249932)
			(stroke
				(width 0.1)
				(type default)
			)
			(layer "B.Fab")
		)
		(fp_text user "+"
			(at 6.322314 0.786384 90)
			(unlocked yes)
			(layer "B.SilkS")
			(effects
				(font
					(size 1.905 1.4224)
					(thickness 0.1524)
				)
				(justify left mirror)
			)
		)
		(fp_text user "-"
			(at -4.8514 -0.14605 180)
			(unlocked yes)
			(layer "B.SilkS")
			(effects
				(font
					(size 1.905 1.4224)
					(thickness 0.1524)
				)
				(justify left mirror)
			)
		)
		(fp_text user "+"
			(at 6.322314 0.786384 90)
			(unlocked yes)
			(layer "B.Fab")
			(effects
				(font
					(size 1.905 1.4224)
					(thickness 0.1524)
				)
				(justify left mirror)
			)
		)
		(fp_text user "-"
			(at -4.8514 -0.14605 180)
			(unlocked yes)
			(layer "B.Fab")
			(effects
				(font
					(size 1.905 1.4224)
					(thickness 0.1524)
				)
				(justify left mirror)
			)
		)
		(pad "1" smd rect
			(at 3.199892 0)
			(size 2.413 2.8194)
			(layers "B.Cu" "B.Mask" "B.Paste")
			(net "PVCCFA_EHV_CPU0")
		)
		(pad "2" smd rect
			(at -3.199892 0)
			(size 2.413 2.8194)
			(layers "B.Cu" "B.Mask" "B.Paste")
			(net "GND")
		)
	)
	(footprint ""
		(layer "B.Cu")
		(at 68.29298 -189.374272 -90)
		(property "Reference" "R290"
			(at 0 0 90)
			(layer "B.SilkS")
			(hide yes)
			(effects
				(font
					(size 1.27 1.27)
				)
				(justify mirror)
			)
		)
		(property "Value" ""
			(at 0 0 90)
			(layer "B.Fab")
			(effects
				(font
					(size 1.27 1.27)
				)
				(justify mirror)
			)
		)
		(duplicate_pad_numbers_are_jumpers no)
		(fp_line
			(start -0.7874 0.4064)
			(end 0.7874 0.4064)
			(stroke
				(width 0.1524)
				(type default)
			)
			(layer "B.SilkS")
		)
		(fp_line
			(start 0.7874 0.4064)
			(end 0.7874 -0.4064)
			(stroke
				(width 0.1524)
				(type default)
			)
			(layer "B.SilkS")
		)
		(fp_line
			(start -0.7874 -0.4064)
			(end -0.7874 0.4064)
			(stroke
				(width 0.1524)
				(type default)
			)
			(layer "B.SilkS")
		)
		(fp_line
			(start 0.7874 -0.4064)
			(end -0.7874 -0.4064)
			(stroke
				(width 0.1524)
				(type default)
			)
			(layer "B.SilkS")
		)
		(fp_line
			(start -0.67945 0.3048)
			(end -0.120396 0.3048)
			(stroke
				(width 0.1)
				(type default)
			)
			(layer "B.Fab")
		)
		(fp_line
			(start -0.120396 0.3048)
			(end -0.120396 0.2794)
			(stroke
				(width 0.1)
				(type default)
			)
			(layer "B.Fab")
		)
		(fp_line
			(start 0.12065 0.3048)
			(end 0.67945 0.3048)
			(stroke
				(width 0.1)
				(type default)
			)
			(layer "B.Fab")
		)
		(fp_line
			(start 0.67945 0.3048)
			(end 0.67945 -0.305054)
			(stroke
				(width 0.1)
				(type default)
			)
			(layer "B.Fab")
		)
		(fp_line
			(start -0.120396 0.2794)
			(end 0.12065 0.2794)
			(stroke
				(width 0.1)
				(type default)
			)
			(layer "B.Fab")
		)
		(fp_line
			(start 0.12065 0.2794)
			(end 0.12065 0.3048)
			(stroke
				(width 0.1)
				(type default)
			)
			(layer "B.Fab")
		)
		(fp_line
			(start -0.12065 -0.2794)
			(end -0.12065 -0.3048)
			(stroke
				(width 0.1)
				(type default)
			)
			(layer "B.Fab")
		)
		(fp_line
			(start 0.12065 -0.2794)
			(end -0.12065 -0.2794)
			(stroke
				(width 0.1)
				(type default)
			)
			(layer "B.Fab")
		)
		(fp_line
			(start -0.67945 -0.3048)
			(end -0.67945 0.3048)
			(stroke
				(width 0.1)
				(type default)
			)
			(layer "B.Fab")
		)
		(fp_line
			(start -0.12065 -0.3048)
			(end -0.67945 -0.3048)
			(stroke
				(width 0.1)
				(type default)
			)
			(layer "B.Fab")
		)
		(fp_line
			(start 0.12065 -0.305054)
			(end 0.12065 -0.2794)
			(stroke
				(width 0.1)
				(type default)
			)
			(layer "B.Fab")
		)
		(fp_line
			(start 0.67945 -0.305054)
			(end 0.12065 -0.305054)
			(stroke
				(width 0.1)
				(type default)
			)
			(layer "B.Fab")
		)
		(pad "1" smd circle
			(at 0.40005 0 90)
			(size 0 0)
			(layers "B.Cu" "B.Mask" "B.Paste")
			(net "GND")
		)
		(pad "2" smd circle
			(at -0.40005 0 90)
			(size 0 0)
			(layers "B.Cu" "B.Mask" "B.Paste")
			(net "PD_CPU1_DMIMODE_OVERRIDE")
		)
	)
	(footprint ""
		(layer "B.Cu")
		(at 321.369182 -39.574724 45)
		(property "Reference" "R1659"
			(at 0 0 45)
			(layer "B.SilkS")
			(hide yes)
			(effects
				(font
					(size 1.27 1.27)
				)
				(justify mirror)
			)
		)
		(property "Value" ""
			(at 0 0 45)
			(layer "B.Fab")
			(effects
				(font
					(size 1.27 1.27)
				)
				(justify mirror)
			)
		)
		(duplicate_pad_numbers_are_jumpers no)
		(fp_line
			(start -0.787389 -0.406267)
			(end -0.787389 0.406267)
			(stroke
				(width 0.1524)
				(type default)
			)
			(layer "B.SilkS")
		)
		(fp_line
			(start -0.787389 0.406267)
			(end 0.787389 0.406267)
			(stroke
				(width 0.1524)
				(type default)
			)
			(layer "B.SilkS")
		)
		(fp_line
			(start 0.787389 -0.406267)
			(end -0.787389 -0.406267)
			(stroke
				(width 0.1524)
				(type default)
			)
			(layer "B.SilkS")
		)
		(fp_line
			(start 0.787389 0.406267)
			(end 0.787389 -0.406267)
			(stroke
				(width 0.1524)
				(type default)
			)
			(layer "B.SilkS")
		)
		(fp_line
			(start -0.679446 -0.30479)
			(end -0.679446 0.30479)
			(stroke
				(width 0.1)
				(type default)
			)
			(layer "B.Fab")
		)
		(fp_line
			(start -0.120515 -0.30479)
			(end -0.679446 -0.30479)
			(stroke
				(width 0.1)
				(type default)
			)
			(layer "B.Fab")
		)
		(fp_line
			(start -0.120695 -0.279466)
			(end -0.120515 -0.30479)
			(stroke
				(width 0.1)
				(type default)
			)
			(layer "B.Fab")
		)
		(fp_line
			(start -0.679446 0.30479)
			(end -0.120515 0.30479)
			(stroke
				(width 0.1)
				(type default)
			)
			(layer "B.Fab")
		)
		(fp_line
			(start 0.120695 -0.304969)
			(end 0.120695 -0.279466)
			(stroke
				(width 0.1)
				(type default)
			)
			(layer "B.Fab")
		)
		(fp_line
			(start 0.120695 -0.279466)
			(end -0.120695 -0.279466)
			(stroke
				(width 0.1)
				(type default)
			)
			(layer "B.Fab")
		)
		(fp_line
			(start -0.120335 0.279466)
			(end 0.120695 0.279466)
			(stroke
				(width 0.1)
				(type default)
			)
			(layer "B.Fab")
		)
		(fp_line
			(start -0.120515 0.30479)
			(end -0.120335 0.279466)
			(stroke
				(width 0.1)
				(type default)
			)
			(layer "B.Fab")
		)
		(fp_line
			(start 0.679446 -0.305149)
			(end 0.120695 -0.304969)
			(stroke
				(width 0.1)
				(type default)
			)
			(layer "B.Fab")
		)
		(fp_line
			(start 0.120695 0.279466)
			(end 0.120515 0.30479)
			(stroke
				(width 0.1)
				(type default)
			)
			(layer "B.Fab")
		)
		(fp_line
			(start 0.120515 0.30479)
			(end 0.679446 0.30479)
			(stroke
				(width 0.1)
				(type default)
			)
			(layer "B.Fab")
		)
		(fp_line
			(start 0.679446 0.30479)
			(end 0.679446 -0.305149)
			(stroke
				(width 0.1)
				(type default)
			)
			(layer "B.Fab")
		)
		(pad "1" smd circle
			(at 0.40005 0 225)
			(size 0 0)
			(layers "B.Cu" "B.Mask" "B.Paste")
			(net "FM_PMBUS_ALERT_B_EN")
		)
		(pad "2" smd circle
			(at -0.40005 0 225)
			(size 0 0)
			(layers "B.Cu" "B.Mask" "B.Paste")
			(net "P3V3_AUX")
		)
	)
)
